# SCM (Grand Teton) — schematic netlist excerpt (pin names and nets, part order shuffled) for the footprints in the layout excerpt that follows; sources: Cadence DE-HDL packaged netlist, KiCad conversion of 12092022_DA0F0TMDCD0_F0T_Management_Board_D_brd_V3_OCP.brd

L17  Q_INDUCTOR  BLM18EG121SN1D/2A IND  pkg SMLF  page 17 : \1\ = PGPPA_BMC_AUX_L ; \2\ = PGPPA_BMC_AUX
R184  Q_RES  110 1% CHIP  pkg 0402LF  page 14 : A = I3C1_SPD_SCL ; B = I3C1_SCL_R

(kicad_pcb
	(version 20260206)
	(generator "pcbnew")
	(generator_version "10.0")
	(general
		(thickness 1.6)
		(legacy_teardrops no)
	)
	(paper "A4")
	(title_block
		(title "12092022_DA0F0TMDCD0_F0T_Management_Board_D_brd_V3_OCP.brd")
		(comment 1 "Grand Teton / footprints 307-308 of 1440")
	)
	(layers
		(0 "F.Cu" signal "TOP")
		(4 "In1.Cu" signal "GND")
		(6 "In2.Cu" signal "IN1")
		(8 "In3.Cu" signal "GND1")
		(10 "In4.Cu" signal "IN2")
		(12 "In5.Cu" signal "VCC")
		(14 "In6.Cu" signal "VCC1")
		(16 "In7.Cu" signal "IN3")
		(18 "In8.Cu" signal "GND2")
		(20 "In9.Cu" signal "IN4")
		(22 "In10.Cu" signal "GND3")
		(2 "B.Cu" signal "BOTTOM")
		(9 "F.Adhes" user "F.Adhesive")
		(11 "B.Adhes" user "B.Adhesive")
		(13 "F.Paste" user "Package Geometry/Pastemask Top")
		(15 "B.Paste" user "Package Geometry/Pastemask Bottom")
		(5 "F.SilkS" user "Ref Des/Silkscreen Top")
		(7 "B.SilkS" user "Ref Des/Silkscreen Bottom")
		(1 "F.Mask" user "Board Geometry/Soldermask Top")
		(3 "B.Mask" user "Board Geometry/Soldermask Bottom")
		(17 "Dwgs.User" user "User.Drawings")
		(19 "Cmts.User" user "User.Comments")
		(21 "Eco1.User" user "User.Eco1")
		(23 "Eco2.User" user "User.Eco2")
		(25 "Edge.Cuts" user "Board Geometry/Outline")
		(27 "Margin" user)
		(31 "F.CrtYd" user "Package Geometry/Place Bound Top")
		(29 "B.CrtYd" user "Package Geometry/Place Bound Bottom")
		(35 "F.Fab" user "Ref Des/Assembly Top")
		(33 "B.Fab" user "Ref Des/Assembly Bottom")
	)
	(footprint ""
		(layer "F.Cu")
		(at 41.859454 -65.776094 -90)
		(property "Reference" "R184"
			(at 0 0 270)
			(layer "F.SilkS")
			(hide yes)
			(effects
				(font
					(size 1.27 1.27)
				)
			)
		)
		(property "Value" ""
			(at 0 0 270)
			(layer "F.Fab")
			(effects
				(font
					(size 1.27 1.27)
				)
			)
		)
		(duplicate_pad_numbers_are_jumpers no)
		(fp_line
			(start -0.7874 0.4064)
			(end -0.7874 -0.4064)
			(stroke
				(width 0.1524)
				(type default)
			)
			(layer "F.SilkS")
		)
		(fp_line
			(start 0.7874 0.4064)
			(end -0.7874 0.4064)
			(stroke
				(width 0.1524)
				(type default)
			)
			(layer "F.SilkS")
		)
		(fp_line
			(start -0.7874 -0.4064)
			(end 0.7874 -0.4064)
			(stroke
				(width 0.1524)
				(type default)
			)
			(layer "F.SilkS")
		)
		(fp_line
			(start 0.7874 -0.4064)
			(end 0.7874 0.4064)
			(stroke
				(width 0.1524)
				(type default)
			)
			(layer "F.SilkS")
		)
		(fp_line
			(start -0.67945 0.3048)
			(end -0.67945 -0.305054)
			(stroke
				(width 0.1)
				(type default)
			)
			(layer "F.Fab")
		)
		(fp_line
			(start -0.12065 0.3048)
			(end -0.67945 0.3048)
			(stroke
				(width 0.1)
				(type default)
			)
			(layer "F.Fab")
		)
		(fp_line
			(start 0.120396 0.3048)
			(end 0.120396 0.2794)
			(stroke
				(width 0.1)
				(type default)
			)
			(layer "F.Fab")
		)
		(fp_line
			(start 0.67945 0.3048)
			(end 0.120396 0.3048)
			(stroke
				(width 0.1)
				(type default)
			)
			(layer "F.Fab")
		)
		(fp_line
			(start -0.12065 0.2794)
			(end -0.12065 0.3048)
			(stroke
				(width 0.1)
				(type default)
			)
			(layer "F.Fab")
		)
		(fp_line
			(start 0.120396 0.2794)
			(end -0.12065 0.2794)
			(stroke
				(width 0.1)
				(type default)
			)
			(layer "F.Fab")
		)
		(fp_line
			(start -0.12065 -0.2794)
			(end 0.12065 -0.2794)
			(stroke
				(width 0.1)
				(type default)
			)
			(layer "F.Fab")
		)
		(fp_line
			(start 0.12065 -0.2794)
			(end 0.12065 -0.3048)
			(stroke
				(width 0.1)
				(type default)
			)
			(layer "F.Fab")
		)
		(fp_line
			(start 0.12065 -0.3048)
			(end 0.67945 -0.3048)
			(stroke
				(width 0.1)
				(type default)
			)
			(layer "F.Fab")
		)
		(fp_line
			(start 0.67945 -0.3048)
			(end 0.67945 0.3048)
			(stroke
				(width 0.1)
				(type default)
			)
			(layer "F.Fab")
		)
		(fp_line
			(start -0.67945 -0.305054)
			(end -0.12065 -0.305054)
			(stroke
				(width 0.1)
				(type default)
			)
			(layer "F.Fab")
		)
		(fp_line
			(start -0.12065 -0.305054)
			(end -0.12065 -0.2794)
			(stroke
				(width 0.1)
				(type default)
			)
			(layer "F.Fab")
		)
		(pad "1" smd circle
			(at -0.40005 0 270)
			(size 0 0)
			(layers "F.Cu" "F.Mask" "F.Paste")
			(net "I3C1_SPD_SCL")
		)
		(pad "2" smd circle
			(at 0.40005 0 270)
			(size 0 0)
			(layers "F.Cu" "F.Mask" "F.Paste")
			(net "I3C1_SCL_R")
		)
	)
	(footprint ""
		(layer "F.Cu")
		(at 63.654432 -66.926968 180)
		(property "Reference" "L17"
			(at 0 0 180)
			(layer "F.SilkS")
			(hide yes)
			(effects
				(font
					(size 1.27 1.27)
				)
			)
		)
		(property "Value" ""
			(at 0 0 180)
			(layer "F.Fab")
			(effects
				(font
					(size 1.27 1.27)
				)
			)
		)
		(duplicate_pad_numbers_are_jumpers no)
		(fp_line
			(start 1.27 0.5842)
			(end 1.27 -0.5842)
			(stroke
				(width 0.1524)
				(type default)
			)
			(layer "F.SilkS")
		)
		(fp_line
			(start 1.27 0.5842)
			(end -1.27 0.5842)
			(stroke
				(width 0.1524)
				(type default)
			)
			(layer "F.SilkS")
		)
		(fp_line
			(start 0.127 0.5842)
			(end 0.127 -0.5842)
			(stroke
				(width 0.1524)
				(type default)
			)
			(layer "F.SilkS")
		)
		(fp_line
			(start -0.127 0.5842)
			(end -0.127 -0.5842)
			(stroke
				(width 0.1524)
				(type default)
			)
			(layer "F.SilkS")
		)
		(fp_line
			(start -1.27 0.5842)
			(end -1.27 -0.5842)
			(stroke
				(width 0.1524)
				(type default)
			)
			(layer "F.SilkS")
		)
		(fp_line
			(start -1.27 -0.5588)
			(end -1.27 -0.5842)
			(stroke
				(width 0.1524)
				(type default)
			)
			(layer "F.SilkS")
		)
		(fp_line
			(start -1.27 -0.5842)
			(end 1.27 -0.5842)
			(stroke
				(width 0.1524)
				(type default)
			)
			(layer "F.SilkS")
		)
		(fp_line
			(start 1.1938 0.4064)
			(end 0.9144 0.4064)
			(stroke
				(width 0.1)
				(type default)
			)
			(layer "F.Fab")
		)
		(fp_line
			(start 1.1938 -0.406654)
			(end 1.1938 0.4064)
			(stroke
				(width 0.1)
				(type default)
			)
			(layer "F.Fab")
		)
		(fp_line
			(start 0.9144 0.508)
			(end -0.9144 0.508)
			(stroke
				(width 0.1)
				(type default)
			)
			(layer "F.Fab")
		)
		(fp_line
			(start 0.9144 0.4064)
			(end 0.9144 0.508)
			(stroke
				(width 0.1)
				(type default)
			)
			(layer "F.Fab")
		)
		(fp_line
			(start 0.9144 -0.406654)
			(end 1.1938 -0.406654)
			(stroke
				(width 0.1)
				(type default)
			)
			(layer "F.Fab")
		)
		(fp_line
			(start 0.9144 -0.508)
			(end 0.9144 -0.406654)
			(stroke
				(width 0.1)
				(type default)
			)
			(layer "F.Fab")
		)
		(fp_line
			(start -0.9144 0.508)
			(end -0.9144 0.406654)
			(stroke
				(width 0.1)
				(type default)
			)
			(layer "F.Fab")
		)
		(fp_line
			(start -0.9144 0.406654)
			(end -1.194308 0.406654)
			(stroke
				(width 0.1)
				(type default)
			)
			(layer "F.Fab")
		)
		(fp_line
			(start -0.9144 -0.406654)
			(end -0.9144 -0.508)
			(stroke
				(width 0.1)
				(type default)
			)
			(layer "F.Fab")
		)
		(fp_line
			(start -0.9144 -0.508)
			(end 0.9144 -0.508)
			(stroke
				(width 0.1)
				(type default)
			)
			(layer "F.Fab")
		)
		(fp_line
			(start -1.194308 0.406654)
			(end -1.194308 -0.406654)
			(stroke
				(width 0.1)
				(type default)
			)
			(layer "F.Fab")
		)
		(fp_line
			(start -1.194308 -0.406654)
			(end -0.9144 -0.406654)
			(stroke
				(width 0.1)
				(type default)
			)
			(layer "F.Fab")
		)
		(pad "1" smd rect
			(at -0.7366 0 90)
			(size 0.7112 0.8128)
			(layers "F.Cu" "F.Mask" "F.Paste")
			(net "PGPPA_BMC_AUX_L")
		)
		(pad "2" smd rect
			(at 0.7366 0 90)
			(size 0.7112 0.8128)
			(layers "F.Cu" "F.Mask" "F.Paste")
			(net "PGPPA_BMC_AUX")
		)
	)
)
